(kicad_pcb
	(version 20260206)
	(generator "pcbnew")
	(generator_version "10.0")
	(general
		(thickness 1.6)
		(legacy_teardrops no)
	)
	(paper "A4")
	(title_block
		(title "03242023_DA0F0TMBIJ0_F0T_Motherboard_J_brd_V01_OCP.brd")
		(comment 1 "Grand Teton / footprint 1682 of 6105 (U1), pads 1062-1168 of 4677")
	)
	(layers
		(0 "F.Cu" signal "TOP")
		(4 "In1.Cu" signal "GND")
		(6 "In2.Cu" signal "IN1")
		(8 "In3.Cu" signal "GND1")
		(10 "In4.Cu" signal "IN2")
		(12 "In5.Cu" signal "GND2")
		(14 "In6.Cu" signal "IN3")
		(16 "In7.Cu" signal "GND3")
		(18 "In8.Cu" signal "VCC")
		(20 "In9.Cu" signal "VCC1")
		(22 "In10.Cu" signal "GND4")
		(24 "In11.Cu" signal "IN4")
		(26 "In12.Cu" signal "GND5")
		(28 "In13.Cu" signal "IN5")
		(30 "In14.Cu" signal "GND6")
		(32 "In15.Cu" signal "IN6")
		(34 "In16.Cu" signal "GND7")
		(2 "B.Cu" signal "BOTTOM")
		(9 "F.Adhes" user "F.Adhesive")
		(11 "B.Adhes" user "B.Adhesive")
		(13 "F.Paste" user "Package Geometry/Pastemask Top")
		(15 "B.Paste" user "Package Geometry/Pastemask Bottom")
		(5 "F.SilkS" user "Ref Des/Silkscreen Top")
		(7 "B.SilkS" user "Ref Des/Silkscreen Bottom")
		(1 "F.Mask" user "Board Geometry/Soldermask Top")
		(3 "B.Mask" user "Board Geometry/Soldermask Bottom")
		(17 "Dwgs.User" user "User.Drawings")
		(19 "Cmts.User" user "User.Comments")
		(21 "Eco1.User" user "User.Eco1")
		(23 "Eco2.User" user "User.Eco2")
		(25 "Edge.Cuts" user "Board Geometry/Outline")
		(27 "Margin" user)
		(31 "F.CrtYd" user "Package Geometry/Place Bound Top")
		(29 "B.CrtYd" user "Package Geometry/Place Bound Bottom")
		(35 "F.Fab" user "Ref Des/Assembly Top")
		(33 "B.Fab" user "Ref Des/Assembly Bottom")
	)
	(footprint ""
		(layer "F.Cu")
		(at 111.93018 -251.76988 90)
		(property "Reference" "U1"
			(at -74.913236 41.548812 0)
			(unlocked yes)
			(layer "F.SilkS")
			(effects
				(font
					(size 1.6002 1.1938)
					(thickness 0.1524)
				)
				(justify left)
			)
		)
		(property "Value" ""
			(at 0 0 90)
			(layer "F.Fab")
			(effects
				(font
					(size 1.27 1.27)
				)
			)
		)
		(duplicate_pad_numbers_are_jumpers no)
		(pad "BE23" smd circle
			(at -19.519392 -6.398514 270)
			(size 0.4318 0.4318)
			(layers "F.Cu" "F.Mask" "F.Paste")
			(net "TP_CPU1_IFST_KOT_LVC1_R")
		)
		(pad "BE25" smd circle
			(at -17.89176 -6.398514 270)
			(size 0.4318 0.4318)
			(layers "F.Cu" "F.Mask" "F.Paste")
			(net "TP_I3C_MNG3_BMC_SW_SCL")
		)
		(pad "BE60" smd circle
			(at 12.19454 -6.288532 270)
			(size 0.4318 0.4318)
			(layers "F.Cu" "F.Mask" "F.Paste")
			(net "PVCCINFAON_CPU1")
		)
		(pad "BE62" smd circle
			(at 13.822426 -6.288532 270)
			(size 0.4318 0.4318)
			(layers "F.Cu" "F.Mask" "F.Paste")
			(net "NC_ESPI_IBL_CPU1_ALERT0_N")
		)
		(pad "BE64" smd circle
			(at 15.450058 -6.288532 270)
			(size 0.4318 0.4318)
			(layers "F.Cu" "F.Mask" "F.Paste")
			(net "GND")
		)
		(pad "BE66" smd circle
			(at 17.07769 -6.288532 270)
			(size 0.4318 0.4318)
			(layers "F.Cu" "F.Mask" "F.Paste")
			(net "GND")
		)
		(pad "BE68" smd circle
			(at 18.705576 -6.288532 270)
			(size 0.4318 0.4318)
			(layers "F.Cu" "F.Mask" "F.Paste")
			(net "GND")
		)
		(pad "BE70" smd circle
			(at 20.333462 -6.288532 270)
			(size 0.4318 0.4318)
			(layers "F.Cu" "F.Mask" "F.Paste")
			(net "TP_TRC_CPU1_PTI<17>")
		)
		(pad "BE72" smd circle
			(at 21.961094 -6.288532 270)
			(size 0.4318 0.4318)
			(layers "F.Cu" "F.Mask" "F.Paste")
			(net "PVCCFA_EHV_FIVRA_CPU1")
		)
		(pad "BE74" smd circle
			(at 23.58898 -6.288532 270)
			(size 0.4318 0.4318)
			(layers "F.Cu" "F.Mask" "F.Paste")
			(net "GND")
		)
		(pad "BE76" smd circle
			(at 25.216612 -6.288532 270)
			(size 0.4318 0.4318)
			(layers "F.Cu" "F.Mask" "F.Paste")
			(net "GND")
		)
		(pad "BE78" smd circle
			(at 26.844498 -6.288532 270)
			(size 0.4318 0.4318)
			(layers "F.Cu" "F.Mask" "F.Paste")
			(net "GND")
		)
		(pad "BE80" smd circle
			(at 28.472384 -6.288532 270)
			(size 0.4318 0.4318)
			(layers "F.Cu" "F.Mask" "F.Paste")
			(net "UPI_CPU1_CPU0_P2P2_DP<22>")
		)
		(pad "BE82" smd circle
			(at 30.100016 -6.288532 270)
			(size 0.4318 0.4318)
			(layers "F.Cu" "F.Mask" "F.Paste")
			(net "UPI_CPU1_CPU0_P2P2_DN<19>")
		)
		(pad "BE84" smd circle
			(at 31.727902 -6.288532 270)
			(size 0.4318 0.4318)
			(layers "F.Cu" "F.Mask" "F.Paste")
			(net "GND")
		)
		(pad "BE86" smd circle
			(at 33.355534 -6.288532 270)
			(size 0.4318 0.4318)
			(layers "F.Cu" "F.Mask" "F.Paste")
			(net "PVCCIN_CPU1")
		)
		(pad "BE88" smd circle
			(at 34.98342 -6.288532 270)
			(size 0.4318 0.4318)
			(layers "F.Cu" "F.Mask" "F.Paste")
			(net "PVCCIN_CPU1")
		)
		(pad "BE90" smd circle
			(at 36.611306 -6.288532 270)
			(size 0.4318 0.4318)
			(layers "F.Cu" "F.Mask" "F.Paste")
			(net "PVCCIN_CPU1")
		)
		(pad "BF2" smd circle
			(at -36.611306 -5.928868 270)
			(size 0.4318 0.4318)
			(layers "F.Cu" "F.Mask" "F.Paste")
			(net "UPI_CPU1_CPU0_P0P1_DN<18>")
		)
		(pad "BF4" smd circle
			(at -34.98342 -5.928868 270)
			(size 0.4318 0.4318)
			(layers "F.Cu" "F.Mask" "F.Paste")
			(net "GND")
		)
		(pad "BF6" smd circle
			(at -33.355534 -5.928868 270)
			(size 0.4318 0.4318)
			(layers "F.Cu" "F.Mask" "F.Paste")
			(net "UPI_CPU0_CPU1_P1P0_DN<18>")
		)
		(pad "BF8" smd circle
			(at -31.727902 -5.928868 270)
			(size 0.4318 0.4318)
			(layers "F.Cu" "F.Mask" "F.Paste")
			(net "GND")
		)
		(pad "BF10" smd circle
			(at -30.100016 -5.928868 270)
			(size 0.4318 0.4318)
			(layers "F.Cu" "F.Mask" "F.Paste")
			(net "P5E_CPU1_PE1_RX_DN<14>")
		)
		(pad "BF12" smd circle
			(at -28.472384 -5.928868 270)
			(size 0.4318 0.4318)
			(layers "F.Cu" "F.Mask" "F.Paste")
			(net "GND")
		)
		(pad "BF14" smd circle
			(at -26.844498 -5.928868 270)
			(size 0.4318 0.4318)
			(layers "F.Cu" "F.Mask" "F.Paste")
			(net "P5E_CPU1_PE1_TX_DN<14>")
		)
		(pad "BF16" smd circle
			(at -25.216612 -5.928868 270)
			(size 0.4318 0.4318)
			(layers "F.Cu" "F.Mask" "F.Paste")
			(net "GND")
		)
		(pad "BF18" smd circle
			(at -23.58898 -5.928868 270)
			(size 0.4318 0.4318)
			(layers "F.Cu" "F.Mask" "F.Paste")
			(net "TP_DMI_CPU1_PCH_RX_C_DN<2>")
		)
		(pad "BF20" smd circle
			(at -21.961094 -5.928868 270)
			(size 0.4318 0.4318)
			(layers "F.Cu" "F.Mask" "F.Paste")
			(net "GND")
		)
		(pad "BF22" smd circle
			(at -20.333462 -5.928868 270)
			(size 0.4318 0.4318)
			(layers "F.Cu" "F.Mask" "F.Paste")
			(net "H_CPU1_ERR0_LVC1_R_N")
		)
		(pad "BF24" smd circle
			(at -18.705576 -5.928868 270)
			(size 0.4318 0.4318)
			(layers "F.Cu" "F.Mask" "F.Paste")
			(net "TP_CPU1_IFST_TRIG_LVC1_R")
		)
		(pad "BF26" smd circle
			(at -17.07769 -5.928868 270)
			(size 0.4318 0.4318)
			(layers "F.Cu" "F.Mask" "F.Paste")
			(net "SVID_CLK1_CPU1")
		)
		(pad "BF61" smd circle
			(at 13.008356 -5.818886 270)
			(size 0.4318 0.4318)
			(layers "F.Cu" "F.Mask" "F.Paste")
			(net "GND")
		)
		(pad "BF63" smd circle
			(at 14.635988 -5.818886 270)
			(size 0.4318 0.4318)
			(layers "F.Cu" "F.Mask" "F.Paste")
			(net "GND")
		)
		(pad "BF65" smd circle
			(at 16.263874 -5.818886 270)
			(size 0.4318 0.4318)
			(layers "F.Cu" "F.Mask" "F.Paste")
			(net "NC_ESPI_IBL_CPU1_CS0_N")
		)
		(pad "BF67" smd circle
			(at 17.89176 -5.818886 270)
			(size 0.4318 0.4318)
			(layers "F.Cu" "F.Mask" "F.Paste")
			(net "TP_TRC_CPU1_PTI2_CLK")
		)
		(pad "BF69" smd circle
			(at 19.519392 -5.818886 270)
			(size 0.4318 0.4318)
			(layers "F.Cu" "F.Mask" "F.Paste")
			(net "TP_TRC_CPU1_PTI<19>")
		)
		(pad "BF71" smd circle
			(at 21.147278 -5.818886 270)
			(size 0.4318 0.4318)
			(layers "F.Cu" "F.Mask" "F.Paste")
			(net "NC_CPU1_MDFI_DIE01_NS0")
		)
		(pad "BF73" smd circle
			(at 22.77491 -5.818886 270)
			(size 0.4318 0.4318)
			(layers "F.Cu" "F.Mask" "F.Paste")
			(net "GND")
		)
		(pad "BF75" smd circle
			(at 24.402796 -5.818886 270)
			(size 0.4318 0.4318)
			(layers "F.Cu" "F.Mask" "F.Paste")
			(net "GND")
		)
		(pad "BF77" smd circle
			(at 26.030682 -5.818886 270)
			(size 0.4318 0.4318)
			(layers "F.Cu" "F.Mask" "F.Paste")
			(net "PVCCFA_EHV_FIVRA_CPU1")
		)
		(pad "BF79" smd circle
			(at 27.658314 -5.818886 270)
			(size 0.4318 0.4318)
			(layers "F.Cu" "F.Mask" "F.Paste")
			(net "GND")
		)
		(pad "BF81" smd circle
			(at 29.2862 -5.818886 270)
			(size 0.4318 0.4318)
			(layers "F.Cu" "F.Mask" "F.Paste")
			(net "UPI_CPU1_CPU0_P2P2_DN<21>")
		)
		(pad "BF83" smd circle
			(at 30.914086 -5.818886 270)
			(size 0.4318 0.4318)
			(layers "F.Cu" "F.Mask" "F.Paste")
			(net "GND")
		)
		(pad "BF85" smd circle
			(at 32.541718 -5.818886 270)
			(size 0.4318 0.4318)
			(layers "F.Cu" "F.Mask" "F.Paste")
			(net "PVCCIN_CPU1")
		)
		(pad "BF87" smd circle
			(at 34.169604 -5.818886 270)
			(size 0.4318 0.4318)
			(layers "F.Cu" "F.Mask" "F.Paste")
			(net "PVCCIN_CPU1")
		)
		(pad "BF89" smd circle
			(at 35.797236 -5.818886 270)
			(size 0.4318 0.4318)
			(layers "F.Cu" "F.Mask" "F.Paste")
			(net "PVCCIN_CPU1")
		)
		(pad "BF91" smd oval
			(at 37.425122 -5.818886)
			(size 0.381 0.4826)
			(drill
				(offset 0 -0.0508)
			)
			(layers "F.Cu" "F.Mask" "F.Paste")
			(net "PVCCIN_CPU1")
		)
		(pad "BG1" smd oval
			(at -37.425122 -5.458714 180)
			(size 0.381 0.4826)
			(drill
				(offset 0 -0.0508)
			)
			(layers "F.Cu" "F.Mask" "F.Paste")
			(net "GND")
		)
		(pad "BG3" smd circle
			(at -35.797236 -5.458714 270)
			(size 0.4318 0.4318)
			(layers "F.Cu" "F.Mask" "F.Paste")
			(net "UPI_CPU1_CPU0_P0P1_DP<19>")
		)
		(pad "BG5" smd circle
			(at -34.169604 -5.458714 270)
			(size 0.4318 0.4318)
			(layers "F.Cu" "F.Mask" "F.Paste")
			(net "GND")
		)
		(pad "BG7" smd circle
			(at -32.541718 -5.458714 270)
			(size 0.4318 0.4318)
			(layers "F.Cu" "F.Mask" "F.Paste")
			(net "UPI_CPU0_CPU1_P1P0_DP<18>")
		)
		(pad "BG9" smd circle
			(at -30.914086 -5.458714 270)
			(size 0.4318 0.4318)
			(layers "F.Cu" "F.Mask" "F.Paste")
			(net "GND")
		)
		(pad "BG11" smd circle
			(at -29.2862 -5.458714 270)
			(size 0.4318 0.4318)
			(layers "F.Cu" "F.Mask" "F.Paste")
			(net "P5E_CPU1_PE1_RX_DN<13>")
		)
		(pad "BG13" smd circle
			(at -27.658314 -5.458714 270)
			(size 0.4318 0.4318)
			(layers "F.Cu" "F.Mask" "F.Paste")
			(net "GND")
		)
		(pad "BG15" smd circle
			(at -26.030682 -5.458714 270)
			(size 0.4318 0.4318)
			(layers "F.Cu" "F.Mask" "F.Paste")
			(net "P5E_CPU1_PE1_TX_DP<14>")
		)
		(pad "BG17" smd circle
			(at -24.402796 -5.458714 270)
			(size 0.4318 0.4318)
			(layers "F.Cu" "F.Mask" "F.Paste")
			(net "GND")
		)
		(pad "BG19" smd circle
			(at -22.77491 -5.458714 270)
			(size 0.4318 0.4318)
			(layers "F.Cu" "F.Mask" "F.Paste")
			(net "TP_DMI_CPU1_PCH_RX_C_DP<2>")
		)
		(pad "BG21" smd circle
			(at -21.147278 -5.458714 270)
			(size 0.4318 0.4318)
			(layers "F.Cu" "F.Mask" "F.Paste")
			(net "GND")
		)
		(pad "BG23" smd circle
			(at -19.519392 -5.458714 270)
			(size 0.4318 0.4318)
			(layers "F.Cu" "F.Mask" "F.Paste")
			(net "GND")
		)
		(pad "BG25" smd circle
			(at -17.89176 -5.458714 270)
			(size 0.4318 0.4318)
			(layers "F.Cu" "F.Mask" "F.Paste")
			(net "GND")
		)
		(pad "BG60" smd circle
			(at 12.19454 -5.348732 270)
			(size 0.4318 0.4318)
			(layers "F.Cu" "F.Mask" "F.Paste")
			(net "PVCCINFAON_CPU1")
		)
		(pad "BG62" smd circle
			(at 13.822426 -5.348732 270)
			(size 0.4318 0.4318)
			(layers "F.Cu" "F.Mask" "F.Paste")
			(net "NC_ESPI_IBL_CPU1_CLK")
		)
		(pad "BG64" smd circle
			(at 15.450058 -5.348732 270)
			(size 0.4318 0.4318)
			(layers "F.Cu" "F.Mask" "F.Paste")
			(net "NC_ESPI_IBL_CPU1_RESET_N")
		)
		(pad "BG66" smd circle
			(at 17.07769 -5.348732 270)
			(size 0.4318 0.4318)
			(layers "F.Cu" "F.Mask" "F.Paste")
			(net "TP_TRC_CPU1_PTI<27>")
		)
		(pad "BG68" smd circle
			(at 18.705576 -5.348732 270)
			(size 0.4318 0.4318)
			(layers "F.Cu" "F.Mask" "F.Paste")
			(net "TP_TRC_CPU1_PTI<22>")
		)
		(pad "BG70" smd circle
			(at 20.333462 -5.348732 270)
			(size 0.4318 0.4318)
			(layers "F.Cu" "F.Mask" "F.Paste")
			(net "GND")
		)
		(pad "BG72" smd circle
			(at 21.961094 -5.348732 270)
			(size 0.4318 0.4318)
			(layers "F.Cu" "F.Mask" "F.Paste")
			(net "FM_CPU1_PROC_ID0")
		)
		(pad "BG74" smd circle
			(at 23.58898 -5.348732 270)
			(size 0.4318 0.4318)
			(layers "F.Cu" "F.Mask" "F.Paste")
			(net "UPI_CPU0_CPU1_P2P2_DN<20>")
		)
		(pad "BG76" smd circle
			(at 25.216612 -5.348732 270)
			(size 0.4318 0.4318)
			(layers "F.Cu" "F.Mask" "F.Paste")
			(net "UPI_CPU0_CPU1_P2P2_DP<17>")
		)
		(pad "BG78" smd circle
			(at 26.844498 -5.348732 270)
			(size 0.4318 0.4318)
			(layers "F.Cu" "F.Mask" "F.Paste")
			(net "NC_CPU1_HBM3_VIEWDIG0")
		)
		(pad "BG80" smd circle
			(at 28.472384 -5.348732 270)
			(size 0.4318 0.4318)
			(layers "F.Cu" "F.Mask" "F.Paste")
			(net "UPI_CPU1_CPU0_P2P2_DN<22>")
		)
		(pad "BG82" smd circle
			(at 30.100016 -5.348732 270)
			(size 0.4318 0.4318)
			(layers "F.Cu" "F.Mask" "F.Paste")
			(net "UPI_CPU1_CPU0_P2P2_DP<21>")
		)
		(pad "BG84" smd circle
			(at 31.727902 -5.348732 270)
			(size 0.4318 0.4318)
			(layers "F.Cu" "F.Mask" "F.Paste")
			(net "PVCCIN_CPU1")
		)
		(pad "BG86" smd circle
			(at 33.355534 -5.348732 270)
			(size 0.4318 0.4318)
			(layers "F.Cu" "F.Mask" "F.Paste")
			(net "PVCCIN_CPU1")
		)
		(pad "BG88" smd circle
			(at 34.98342 -5.348732 270)
			(size 0.4318 0.4318)
			(layers "F.Cu" "F.Mask" "F.Paste")
			(net "PVCCIN_CPU1")
		)
		(pad "BG90" smd circle
			(at 36.611306 -5.348732 270)
			(size 0.4318 0.4318)
			(layers "F.Cu" "F.Mask" "F.Paste")
			(net "PVCCIN_CPU1")
		)
		(pad "BH2" smd circle
			(at -36.611306 -4.989068 270)
			(size 0.4318 0.4318)
			(layers "F.Cu" "F.Mask" "F.Paste")
			(net "UPI_CPU1_CPU0_P0P1_DN<19>")
		)
		(pad "BH4" smd circle
			(at -34.98342 -4.989068 270)
			(size 0.4318 0.4318)
			(layers "F.Cu" "F.Mask" "F.Paste")
			(net "GND")
		)
		(pad "BH6" smd circle
			(at -33.355534 -4.989068 270)
			(size 0.4318 0.4318)
			(layers "F.Cu" "F.Mask" "F.Paste")
			(net "UPI_CPU0_CPU1_P1P0_DP<19>")
		)
		(pad "BH8" smd circle
			(at -31.727902 -4.989068 270)
			(size 0.4318 0.4318)
			(layers "F.Cu" "F.Mask" "F.Paste")
			(net "GND")
		)
		(pad "BH10" smd circle
			(at -30.100016 -4.989068 270)
			(size 0.4318 0.4318)
			(layers "F.Cu" "F.Mask" "F.Paste")
			(net "P5E_CPU1_PE1_RX_DP<13>")
		)
		(pad "BH12" smd circle
			(at -28.472384 -4.989068 270)
			(size 0.4318 0.4318)
			(layers "F.Cu" "F.Mask" "F.Paste")
			(net "GND")
		)
		(pad "BH14" smd circle
			(at -26.844498 -4.989068 270)
			(size 0.4318 0.4318)
			(layers "F.Cu" "F.Mask" "F.Paste")
			(net "P5E_CPU1_PE1_TX_DP<13>")
		)
		(pad "BH16" smd circle
			(at -25.216612 -4.989068 270)
			(size 0.4318 0.4318)
			(layers "F.Cu" "F.Mask" "F.Paste")
			(net "GND")
		)
		(pad "BH18" smd circle
			(at -23.58898 -4.989068 270)
			(size 0.4318 0.4318)
			(layers "F.Cu" "F.Mask" "F.Paste")
			(net "TP_DMI_CPU1_PCH_RX_C_DP<3>")
		)
		(pad "BH20" smd circle
			(at -21.961094 -4.989068 270)
			(size 0.4318 0.4318)
			(layers "F.Cu" "F.Mask" "F.Paste")
			(net "GND")
		)
		(pad "BH22" smd circle
			(at -20.333462 -4.989068 270)
			(size 0.4318 0.4318)
			(layers "F.Cu" "F.Mask" "F.Paste")
			(net "H_CPU1_RMCA_LVC1_R_N")
		)
		(pad "BH24" smd circle
			(at -18.705576 -4.989068 270)
			(size 0.4318 0.4318)
			(layers "F.Cu" "F.Mask" "F.Paste")
			(net "PECI_CPU1_GTL_R")
		)
		(pad "BH26" smd circle
			(at -17.07769 -4.989068 270)
			(size 0.4318 0.4318)
			(layers "F.Cu" "F.Mask" "F.Paste")
			(net "SVID_CLK0_CPU1")
		)
		(pad "BH61" smd circle
			(at 13.008356 -4.879086 270)
			(size 0.4318 0.4318)
			(layers "F.Cu" "F.Mask" "F.Paste")
			(net "RST_CPU1_LVC1_N")
		)
		(pad "BH63" smd circle
			(at 14.635988 -4.879086 270)
			(size 0.4318 0.4318)
			(layers "F.Cu" "F.Mask" "F.Paste")
			(net "NC_ESPI_IBL_CPU1_OE_N")
		)
		(pad "BH65" smd circle
			(at 16.263874 -4.879086 270)
			(size 0.4318 0.4318)
			(layers "F.Cu" "F.Mask" "F.Paste")
			(net "NC_ESPI_IBL_CPU1_CS1_N")
		)
		(pad "BH67" smd circle
			(at 17.89176 -4.879086 270)
			(size 0.4318 0.4318)
			(layers "F.Cu" "F.Mask" "F.Paste")
			(net "GND")
		)
		(pad "BH69" smd circle
			(at 19.519392 -4.879086 270)
			(size 0.4318 0.4318)
			(layers "F.Cu" "F.Mask" "F.Paste")
			(net "TP_TRC_CPU1_PTI<20>")
		)
		(pad "BH71" smd circle
			(at 21.147278 -4.879086 270)
			(size 0.4318 0.4318)
			(layers "F.Cu" "F.Mask" "F.Paste")
			(net "FM_CPU1_PROC_ID1")
		)
		(pad "BH73" smd circle
			(at 22.77491 -4.879086 270)
			(size 0.4318 0.4318)
			(layers "F.Cu" "F.Mask" "F.Paste")
			(net "GND")
		)
		(pad "BH75" smd circle
			(at 24.402796 -4.879086 270)
			(size 0.4318 0.4318)
			(layers "F.Cu" "F.Mask" "F.Paste")
			(net "UPI_CPU0_CPU1_P2P2_DN<17>")
		)
		(pad "BH77" smd circle
			(at 26.030682 -4.879086 270)
			(size 0.4318 0.4318)
			(layers "F.Cu" "F.Mask" "F.Paste")
			(net "GND")
		)
		(pad "BH79" smd circle
			(at 27.658314 -4.879086 270)
			(size 0.4318 0.4318)
			(layers "F.Cu" "F.Mask" "F.Paste")
			(net "PVCCFA_EHV_FIVRA_CPU1")
		)
		(pad "BH81" smd circle
			(at 29.2862 -4.879086 270)
			(size 0.4318 0.4318)
			(layers "F.Cu" "F.Mask" "F.Paste")
			(net "GND")
		)
		(pad "BH83" smd circle
			(at 30.914086 -4.879086 270)
			(size 0.4318 0.4318)
			(layers "F.Cu" "F.Mask" "F.Paste")
			(net "GND")
		)
		(pad "BH85" smd circle
			(at 32.541718 -4.879086 270)
			(size 0.4318 0.4318)
			(layers "F.Cu" "F.Mask" "F.Paste")
			(net "PVCCIN_CPU1")
		)
		(pad "BH87" smd circle
			(at 34.169604 -4.879086 270)
			(size 0.4318 0.4318)
			(layers "F.Cu" "F.Mask" "F.Paste")
			(net "PVCCIN_CPU1")
		)
		(pad "BH89" smd circle
			(at 35.797236 -4.879086 270)
			(size 0.4318 0.4318)
			(layers "F.Cu" "F.Mask" "F.Paste")
			(net "PVCCIN_CPU1")
		)
		(pad "BH91" smd oval
			(at 37.425122 -4.879086)
			(size 0.381 0.4826)
			(drill
				(offset 0 -0.0508)
			)
			(layers "F.Cu" "F.Mask" "F.Paste")
			(net "PVCCIN_CPU1")
		)
		(pad "BJ1" smd oval
			(at -37.425122 -4.518914 180)
			(size 0.381 0.4826)
			(drill
				(offset 0 -0.0508)
			)
			(layers "F.Cu" "F.Mask" "F.Paste")
			(net "UPI_CPU1_CPU0_P0P1_DP<20>")
		)
		(pad "BJ3" smd circle
			(at -35.797236 -4.518914 270)
			(size 0.4318 0.4318)
			(layers "F.Cu" "F.Mask" "F.Paste")
			(net "PVCCD_HV_CPU1")
		)
	)
)
